(kicad_pcb
	(version 20260206)
	(generator "pcbnew")
	(generator_version "10.0")
	(general
		(thickness 1.6)
		(legacy_teardrops no)
	)
	(paper "A4")
	(title_block
		(title "v1-chassis-manager — T6M_CM_d_v01_1031_1645.brd")
		(comment 1 "Open CloudServer (Microsoft) / footprint 1308 of 2512 (U125), pads 118-128 of 128")
	)
	(layers
		(0 "F.Cu" signal "TOP")
		(4 "In1.Cu" signal "GND1")
		(6 "In2.Cu" signal "IN1")
		(8 "In3.Cu" signal "VCC1")
		(10 "In4.Cu" signal "VCC2")
		(12 "In5.Cu" signal "GND2")
		(14 "In6.Cu" signal "IN2")
		(16 "In7.Cu" signal "IN3")
		(18 "In8.Cu" signal "GND3")
		(2 "B.Cu" signal "BOTTOM")
		(9 "F.Adhes" user "F.Adhesive")
		(11 "B.Adhes" user "B.Adhesive")
		(13 "F.Paste" user "Package Geometry/Pastemask Top")
		(15 "B.Paste" user "Package Geometry/Pastemask Bottom")
		(5 "F.SilkS" user "Ref Des/Silkscreen Top")
		(7 "B.SilkS" user "Ref Des/Silkscreen Bottom")
		(1 "F.Mask" user "Board Geometry/Soldermask Top")
		(3 "B.Mask" user "Board Geometry/Soldermask Bottom")
		(17 "Dwgs.User" user "User.Drawings")
		(19 "Cmts.User" user "User.Comments")
		(21 "Eco1.User" user "User.Eco1")
		(23 "Eco2.User" user "User.Eco2")
		(25 "Edge.Cuts" user "Board Geometry/Outline")
		(27 "Margin" user)
		(31 "F.CrtYd" user "Package Geometry/Place Bound Top")
		(29 "B.CrtYd" user "Package Geometry/Place Bound Bottom")
		(35 "F.Fab" user "Ref Des/Assembly Top")
		(33 "B.Fab" user "Ref Des/Assembly Bottom")
	)
	(footprint ""
		(layer "F.Cu")
		(at 133.53796 -143.575532 90)
		(property "Reference" "U125"
			(at -10.804652 0.525272 0)
			(unlocked yes)
			(layer "F.SilkS")
			(effects
				(font
					(size 0.7874 0.5842)
					(thickness 0.1524)
				)
				(justify left)
			)
		)
		(property "Value" ""
			(at 0 0 90)
			(layer "F.Fab")
			(effects
				(font
					(size 1.27 1.27)
				)
			)
		)
		(duplicate_pad_numbers_are_jumpers no)
		(pad "118" smd rect
			(at -7.750048 2.199894 180)
			(size 0.1778 1.524)
			(layers "F.Cu" "F.Mask" "F.Paste")
			(net "P1V0_NODE1")
		)
		(pad "119" smd rect
			(at -7.750048 2.599944 180)
			(size 0.1778 1.524)
			(layers "F.Cu" "F.Mask" "F.Paste")
			(net "GND")
		)
		(pad "120" smd rect
			(at -7.750048 2.999994 180)
			(size 0.1778 1.524)
			(layers "F.Cu" "F.Mask" "F.Paste")
			(net "Net_2277")
		)
		(pad "121" smd rect
			(at -7.750048 3.400044 180)
			(size 0.1778 1.524)
			(layers "F.Cu" "F.Mask" "F.Paste")
			(net "Net_2276")
		)
		(pad "122" smd rect
			(at -7.750048 3.800094 180)
			(size 0.1778 1.524)
			(layers "F.Cu" "F.Mask" "F.Paste")
			(net "GND")
		)
		(pad "123" smd rect
			(at -7.750048 4.19989 180)
			(size 0.1778 1.524)
			(layers "F.Cu" "F.Mask" "F.Paste")
			(net "P1V0_NODE1")
		)
		(pad "124" smd rect
			(at -7.750048 4.59994 180)
			(size 0.1778 1.524)
			(layers "F.Cu" "F.Mask" "F.Paste")
			(net "P3V3_NODE1")
		)
		(pad "125" smd rect
			(at -7.750048 4.99999 180)
			(size 0.1778 1.524)
			(layers "F.Cu" "F.Mask" "F.Paste")
			(net "GND")
		)
		(pad "126" smd rect
			(at -7.750048 5.40004 180)
			(size 0.1778 1.524)
			(layers "F.Cu" "F.Mask" "F.Paste")
			(net "PCIE_SW_TEST6")
		)
		(pad "127" smd rect
			(at -7.750048 5.80009 180)
			(size 0.1778 1.524)
			(layers "F.Cu" "F.Mask" "F.Paste")
			(net "PCIE_SW_SLOTCLK")
		)
		(pad "128" smd rect
			(at -7.750048 6.199886 180)
			(size 0.1778 1.524)
			(layers "F.Cu" "F.Mask" "F.Paste")
			(net "PCIE_SW_PRSNT1")
		)
	)
)
